# BASEBOARD_FAB2 (Tioga Pass) — schematic netlist excerpt (pin names and nets, part order shuffled) for the footprints in the layout excerpt that follows; sources: Cadence DE-HDL packaged netlist, KiCad conversion of Wiwynn_Tioga_Pass_MB.brd

R8G18  RES  0.0 5% CHIP  pkg 0402  page 189 : A = JTAG_PLD_TCK ; B = JTAG_PLD_TCK_MUX
C5G1  CAP_A  47UF 4V 20% X5R  pkg 0603V  page 217 : A = PVDDQ_ABC ; B = GND
R6N2  RES  100.0 1% CHIP  pkg 0402  page 21 : A = SVID_DIO0_CPU0_R ; B = PVCCIO_CPU0

(kicad_pcb
	(version 20260206)
	(generator "pcbnew")
	(generator_version "10.0")
	(general
		(thickness 1.6)
		(legacy_teardrops no)
	)
	(paper "A4")
	(title_block
		(title "Wiwynn_Tioga_Pass_MB.brd")
		(comment 1 "Tioga Pass / footprints 392-394 of 4770")
	)
	(layers
		(0 "F.Cu" signal "TOP")
		(4 "In1.Cu" signal "L2GND")
		(6 "In2.Cu" signal "L3")
		(8 "In3.Cu" signal "L4GND")
		(10 "In4.Cu" signal "L5")
		(12 "In5.Cu" signal "L6GND")
		(14 "In6.Cu" signal "L7VCC")
		(16 "In7.Cu" signal "L8VCC")
		(18 "In8.Cu" signal "L9GND")
		(20 "In9.Cu" signal "L10")
		(22 "In10.Cu" signal "L11GND")
		(24 "In11.Cu" signal "L12")
		(26 "In12.Cu" signal "L13GND")
		(2 "B.Cu" signal "BOTTOM")
		(9 "F.Adhes" user "F.Adhesive")
		(11 "B.Adhes" user "B.Adhesive")
		(13 "F.Paste" user "Package Geometry/Pastemask Top")
		(15 "B.Paste" user "Package Geometry/Pastemask Bottom")
		(5 "F.SilkS" user "Ref Des/Silkscreen Top")
		(7 "B.SilkS" user "Ref Des/Silkscreen Bottom")
		(1 "F.Mask" user "Board Geometry/Soldermask Top")
		(3 "B.Mask" user "Board Geometry/Soldermask Bottom")
		(17 "Dwgs.User" user "User.Drawings")
		(19 "Cmts.User" user "User.Comments")
		(21 "Eco1.User" user "User.Eco1")
		(23 "Eco2.User" user "User.Eco2")
		(25 "Edge.Cuts" user "Board Geometry/Outline")
		(27 "Margin" user)
		(31 "F.CrtYd" user "Package Geometry/Place Bound Top")
		(29 "B.CrtYd" user "Package Geometry/Place Bound Bottom")
		(35 "F.Fab" user "Ref Des/Assembly Top")
		(33 "B.Fab" user "Ref Des/Assembly Bottom")
	)
	(footprint ""
		(layer "F.Cu")
		(at 245.7577 -12.954 -90)
		(property "Reference" "C5G1"
			(at 1.848866 0.752348 270)
			(unlocked yes)
			(layer "F.SilkS")
			(effects
				(font
					(size 1.27 0.9652)
					(thickness 0.1524)
				)
			)
		)
		(property "Value" ""
			(at 0 0 270)
			(layer "F.Fab")
			(effects
				(font
					(size 1.27 1.27)
				)
			)
		)
		(duplicate_pad_numbers_are_jumpers no)
		(fp_rect
			(start -0.500126 1.598422)
			(end 0.500126 -0.201422)
			(stroke
				(width 0)
				(type default)
			)
			(fill no)
			(layer "F.CrtYd")
		)
		(fp_line
			(start -0.500126 1.598422)
			(end -0.500126 -0.201422)
			(stroke
				(width 0.1)
				(type default)
			)
			(layer "F.Fab")
		)
		(fp_line
			(start 0.500126 1.598422)
			(end -0.500126 1.598422)
			(stroke
				(width 0.1)
				(type default)
			)
			(layer "F.Fab")
		)
		(fp_line
			(start -0.500126 -0.201422)
			(end 0.500126 -0.201422)
			(stroke
				(width 0.1)
				(type default)
			)
			(layer "F.Fab")
		)
		(fp_line
			(start 0.500126 -0.201422)
			(end 0.500126 1.598422)
			(stroke
				(width 0.1)
				(type default)
			)
			(layer "F.Fab")
		)
		(pad "1" smd rect
			(at 0 0 180)
			(size 0.889 0.9906)
			(layers "F.Cu" "F.Mask" "F.Paste")
			(net "PVDDQ_ABC")
		)
		(pad "2" smd rect
			(at 0 1.397 180)
			(size 0.889 0.9906)
			(layers "F.Cu" "F.Mask" "F.Paste")
			(net "GND")
		)
		(zone
			(layer "F.Cu")
			(hatch none 0.5)
			(connect_pads
				(clearance 0)
			)
			(min_thickness 0.25)
			(keepout
				(tracks allowed)
				(vias not_allowed)
				(pads allowed)
				(copperpour not_allowed)
				(footprints allowed)
			)
			(placement
				(enabled no)
				(sheetname "")
			)
			(fill
				(thermal_gap 0.5)
				(thermal_bridge_width 0.5)
				(island_removal_mode 0)
			)
			(polygon
				(pts
					(xy 244.8052 -13.4493) (xy 244.8052 -12.4587) (xy 245.3132 -12.4587) (xy 245.3132 -13.4493)
				)
			)
		)
		(zone
			(layer "F.Cu")
			(hatch none 0.5)
			(connect_pads
				(clearance 0)
			)
			(min_thickness 0.25)
			(keepout
				(tracks not_allowed)
				(vias allowed)
				(pads allowed)
				(copperpour not_allowed)
				(footprints allowed)
			)
			(placement
				(enabled no)
				(sheetname "")
			)
			(fill
				(thermal_gap 0.5)
				(thermal_bridge_width 0.5)
				(island_removal_mode 0)
			)
			(polygon
				(pts
					(xy 244.8052 -13.4493) (xy 244.8052 -12.4587) (xy 245.3132 -12.4587) (xy 245.3132 -13.4493)
				)
			)
		)
	)
	(footprint ""
		(layer "F.Cu")
		(at 204.089 -106.68 90)
		(property "Reference" "R6N2"
			(at -0.8382 -0.67818 90)
			(unlocked yes)
			(layer "F.SilkS")
			(effects
				(font
					(size 0.4064 0.254)
					(thickness 0.1524)
				)
				(justify left)
			)
		)
		(property "Value" ""
			(at 0 0 90)
			(layer "F.Fab")
			(effects
				(font
					(size 1.27 1.27)
				)
			)
		)
		(duplicate_pad_numbers_are_jumpers no)
		(fp_poly
			(pts
				(xy -0.2794 -0.1016) (xy 0.2794 -0.1016) (xy 0.2794 0.9906) (xy -0.2794 0.9906)
			)
			(stroke
				(width 0)
				(type default)
			)
			(fill no)
			(layer "F.CrtYd")
		)
		(fp_line
			(start 0.2794 -0.1016)
			(end -0.2794 -0.1016)
			(stroke
				(width 0.1)
				(type default)
			)
			(layer "F.Fab")
		)
		(fp_line
			(start -0.2794 -0.1016)
			(end -0.2794 0.9906)
			(stroke
				(width 0.1)
				(type default)
			)
			(layer "F.Fab")
		)
		(fp_line
			(start 0.2794 0.9906)
			(end 0.2794 -0.1016)
			(stroke
				(width 0.1)
				(type default)
			)
			(layer "F.Fab")
		)
		(fp_line
			(start -0.2794 0.9906)
			(end 0.2794 0.9906)
			(stroke
				(width 0.1)
				(type default)
			)
			(layer "F.Fab")
		)
		(pad "1" smd rect
			(at 0 0 90)
			(size 0.508 0.508)
			(layers "F.Cu" "F.Mask" "F.Paste")
			(net "SVID_DIO0_CPU0_R")
		)
		(pad "2" smd rect
			(at 0 0.889 90)
			(size 0.508 0.508)
			(layers "F.Cu" "F.Mask" "F.Paste")
			(net "PVCCIO_CPU0")
		)
		(zone
			(layer "F.Cu")
			(hatch none 0.5)
			(connect_pads
				(clearance 0)
			)
			(min_thickness 0.25)
			(keepout
				(tracks allowed)
				(vias not_allowed)
				(pads allowed)
				(copperpour not_allowed)
				(footprints allowed)
			)
			(placement
				(enabled no)
				(sheetname "")
			)
			(fill
				(thermal_gap 0.5)
				(thermal_bridge_width 0.5)
				(island_removal_mode 0)
			)
			(polygon
				(pts
					(xy 204.343 -106.426) (xy 204.343 -106.934) (xy 204.724 -106.934) (xy 204.724 -106.426)
				)
			)
		)
		(zone
			(layer "F.Cu")
			(hatch none 0.5)
			(connect_pads
				(clearance 0)
			)
			(min_thickness 0.25)
			(keepout
				(tracks not_allowed)
				(vias allowed)
				(pads allowed)
				(copperpour not_allowed)
				(footprints allowed)
			)
			(placement
				(enabled no)
				(sheetname "")
			)
			(fill
				(thermal_gap 0.5)
				(thermal_bridge_width 0.5)
				(island_removal_mode 0)
			)
			(polygon
				(pts
					(xy 204.724 -106.426) (xy 204.724 -106.934) (xy 204.343 -106.934) (xy 204.343 -106.426)
				)
			)
		)
	)
	(footprint ""
		(layer "F.Cu")
		(at 399.770092 0.779526 90)
		(property "Reference" "R8G18"
			(at 0 0 90)
			(layer "F.SilkS")
			(hide yes)
			(effects
				(font
					(size 1.27 1.27)
				)
			)
		)
		(property "Value" ""
			(at 0 0 90)
			(layer "F.Fab")
			(effects
				(font
					(size 1.27 1.27)
				)
			)
		)
		(duplicate_pad_numbers_are_jumpers no)
		(fp_poly
			(pts
				(xy -0.2794 -0.1016) (xy 0.2794 -0.1016) (xy 0.2794 0.9906) (xy -0.2794 0.9906)
			)
			(stroke
				(width 0)
				(type default)
			)
			(fill no)
			(layer "F.CrtYd")
		)
		(fp_line
			(start 0.2794 -0.1016)
			(end -0.2794 -0.1016)
			(stroke
				(width 0.1)
				(type default)
			)
			(layer "F.Fab")
		)
		(fp_line
			(start -0.2794 -0.1016)
			(end -0.2794 0.9906)
			(stroke
				(width 0.1)
				(type default)
			)
			(layer "F.Fab")
		)
		(fp_line
			(start 0.2794 0.9906)
			(end 0.2794 -0.1016)
			(stroke
				(width 0.1)
				(type default)
			)
			(layer "F.Fab")
		)
		(fp_line
			(start -0.2794 0.9906)
			(end 0.2794 0.9906)
			(stroke
				(width 0.1)
				(type default)
			)
			(layer "F.Fab")
		)
		(pad "1" smd rect
			(at 0 0 90)
			(size 0.508 0.508)
			(layers "F.Cu" "F.Mask" "F.Paste")
			(net "JTAG_PLD_TCK")
		)
		(pad "2" smd rect
			(at 0 0.889 90)
			(size 0.508 0.508)
			(layers "F.Cu" "F.Mask" "F.Paste")
			(net "JTAG_PLD_TCK_MUX")
		)
		(zone
			(layer "F.Cu")
			(hatch none 0.5)
			(connect_pads
				(clearance 0)
			)
			(min_thickness 0.25)
			(keepout
				(tracks allowed)
				(vias not_allowed)
				(pads allowed)
				(copperpour not_allowed)
				(footprints allowed)
			)
			(placement
				(enabled no)
				(sheetname "")
			)
			(fill
				(thermal_gap 0.5)
				(thermal_bridge_width 0.5)
				(island_removal_mode 0)
			)
			(polygon
				(pts
					(xy 400.024092 1.033526) (xy 400.024092 0.525526) (xy 400.405092 0.525526) (xy 400.405092 1.033526)
				)
			)
		)
		(zone
			(layer "F.Cu")
			(hatch none 0.5)
			(connect_pads
				(clearance 0)
			)
			(min_thickness 0.25)
			(keepout
				(tracks not_allowed)
				(vias allowed)
				(pads allowed)
				(copperpour not_allowed)
				(footprints allowed)
			)
			(placement
				(enabled no)
				(sheetname "")
			)
			(fill
				(thermal_gap 0.5)
				(thermal_bridge_width 0.5)
				(island_removal_mode 0)
			)
			(polygon
				(pts
					(xy 400.405092 1.033526) (xy 400.405092 0.525526) (xy 400.024092 0.525526) (xy 400.024092 1.033526)
				)
			)
		)
	)
)
